FILE_TYPE=LIBRARY_PARTS;
primitive 'PI6CV304LE';
  pin
    'CLK_IN':
      PIN_NUMBER='(1)';
      INPUT_LOAD='(-0.01,0.01)';
    'OE':
      PIN_NUMBER='(2)';
      INPUT_LOAD='(-0.01,0.01)';
    'Y0':
      PIN_NUMBER='(3)';
      OUTPUT_LOAD='(1.0,-1.0)';
    'Y1':
      PIN_NUMBER='(5)';
      OUTPUT_LOAD='(1.0,-1.0)';
    'Y2':
      PIN_NUMBER='(7)';
      OUTPUT_LOAD='(1.0,-1.0)';
    'Y3':
      PIN_NUMBER='(8)';
      OUTPUT_LOAD='(1.0,-1.0)';
    'VDD':
      PIN_NUMBER='(6)';
      PINUSE='POWER';
      NO_LOAD_CHECK='Both';
      NO_IO_CHECK='Both';
      NO_ASSERT_CHECK='TRUE';
      NO_DIR_CHECK='TRUE';
      ALLOW_CONNECT='TRUE';
    'GND':
      PIN_NUMBER='(4)';
      PINUSE='POWER';
      NO_LOAD_CHECK='Both';
      NO_IO_CHECK='Both';
      NO_ASSERT_CHECK='TRUE';
      NO_DIR_CHECK='TRUE';
      ALLOW_CONNECT='TRUE';
  end_pin;
  body
    PART_NAME='PI6CV304LE';
    BODY_NAME='PI6CV304LE';
    PHYS_DES_PREFIX='U';
    CLASS='IC';
  end_body;
end_primitive;

END.
